(kicad_pcb
	(version 20260206)
	(generator "pcbnew")
	(generator_version "10.0")
	(general
		(thickness 1.6)
		(legacy_teardrops no)
	)
	(paper "A4")
	(title_block
		(title "fcb — Lightning_FCB_BRD.brd")
		(comment 1 "Lightning (Wiwynn / Facebook NVMe JBOF) / footprints 314-319 of 495")
	)
	(layers
		(0 "F.Cu" signal "TOP")
		(4 "In1.Cu" signal "L2GND")
		(6 "In2.Cu" signal "L3VCC")
		(2 "B.Cu" signal "BOTTOM")
		(9 "F.Adhes" user "F.Adhesive")
		(11 "B.Adhes" user "B.Adhesive")
		(13 "F.Paste" user "Package Geometry/Pastemask Top")
		(15 "B.Paste" user "Package Geometry/Pastemask Bottom")
		(5 "F.SilkS" user "Ref Des/Silkscreen Top")
		(7 "B.SilkS" user "Ref Des/Silkscreen Bottom")
		(1 "F.Mask" user "Board Geometry/Soldermask Top")
		(3 "B.Mask" user "Board Geometry/Soldermask Bottom")
		(17 "Dwgs.User" user "User.Drawings")
		(19 "Cmts.User" user "User.Comments")
		(21 "Eco1.User" user "User.Eco1")
		(23 "Eco2.User" user "User.Eco2")
		(25 "Edge.Cuts" user "Board Geometry/Outline")
		(27 "Margin" user)
		(31 "F.CrtYd" user "Package Geometry/Place Bound Top")
		(29 "B.CrtYd" user "Package Geometry/Place Bound Bottom")
		(35 "F.Fab" user "Ref Des/Assembly Top")
		(33 "B.Fab" user "Ref Des/Assembly Bottom")
	)
	(footprint ""
		(layer "F.Cu")
		(at 37.8968 -139.9794 180)
		(property "Reference" "PU7"
			(at 0 0 180)
			(layer "F.SilkS")
			(hide yes)
			(effects
				(font
					(size 1.27 1.27)
				)
			)
		)
		(property "Value" "TPS2490DGSR-GP"
			(at 0 -11.1252 180)
			(unlocked yes)
			(layer "F.Fab")
			(hide yes)
			(effects
				(font
					(size 1.016 1.016)
					(thickness 0.1524)
				)
			)
		)
		(property "Device Type" "MSOP10H44"
			(at 0 -12.6492 180)
			(unlocked yes)
			(layer "F.Fab")
			(hide yes)
			(effects
				(font
					(size 1.016 1.016)
					(thickness 0.1524)
				)
			)
		)
		(duplicate_pad_numbers_are_jumpers no)
		(fp_line
			(start 1.143 1.016)
			(end -2.0066 1.016)
			(stroke
				(width 0.1524)
				(type default)
			)
			(layer "F.SilkS")
		)
		(fp_line
			(start 1.143 -1.016)
			(end 1.143 1.016)
			(stroke
				(width 0.1524)
				(type default)
			)
			(layer "F.SilkS")
		)
		(fp_line
			(start -1.5748 0)
			(end -1.9558 0.381)
			(stroke
				(width 0.1524)
				(type default)
			)
			(layer "F.SilkS")
		)
		(fp_line
			(start -1.5748 0)
			(end -1.9558 -0.381)
			(stroke
				(width 0.1524)
				(type default)
			)
			(layer "F.SilkS")
		)
		(fp_line
			(start -1.8288 1.016)
			(end -1.8288 3.048)
			(stroke
				(width 0.508)
				(type default)
			)
			(layer "F.SilkS")
		)
		(fp_line
			(start -2.0066 1.016)
			(end -2.0066 -1.016)
			(stroke
				(width 0.1524)
				(type default)
			)
			(layer "F.SilkS")
		)
		(fp_line
			(start -2.0066 -1.016)
			(end 1.143 -1.016)
			(stroke
				(width 0.1524)
				(type default)
			)
			(layer "F.SilkS")
		)
		(fp_poly
			(pts
				(xy -2.0828 3.3401) (xy 2.0828 3.3401) (xy 2.0828 -3.3401) (xy -2.0828 -3.3401)
			)
			(stroke
				(width 0)
				(type default)
			)
			(fill no)
			(layer "F.CrtYd")
		)
		(fp_poly
			(pts
				(xy -2.0828 3.3401) (xy 2.0828 3.3401) (xy 2.0828 -3.3401) (xy -2.0828 -3.3401)
			)
			(stroke
				(width 0)
				(type default)
			)
			(fill no)
			(layer "F.Fab")
		)
		(pad "1" smd rect
			(at -0.99949 2.0701 180)
			(size 0.3048 1.524)
			(layers "F.Cu" "F.Mask" "F.Paste")
			(net "P12VL_2490_EN_2")
		)
		(pad "2" smd rect
			(at -0.50038 2.0701 180)
			(size 0.3048 1.524)
			(layers "F.Cu" "F.Mask" "F.Paste")
			(net "P12VL_2490_VREF")
		)
		(pad "3" smd rect
			(at 0 2.0701 180)
			(size 0.3048 1.524)
			(layers "F.Cu" "F.Mask" "F.Paste")
			(net "P12VL_2490_PROG")
		)
		(pad "4" smd rect
			(at 0.50038 2.0701 180)
			(size 0.3048 1.524)
			(layers "F.Cu" "F.Mask" "F.Paste")
			(net "P12VL_2490_TIMER")
		)
		(pad "5" smd rect
			(at 0.99949 2.0701 180)
			(size 0.3048 1.524)
			(layers "F.Cu" "F.Mask" "F.Paste")
			(net "GND")
		)
		(pad "6" smd rect
			(at 0.99949 -2.0701 180)
			(size 0.3048 1.524)
			(layers "F.Cu" "F.Mask" "F.Paste")
			(net "P12VL_2490_PG")
		)
		(pad "7" smd rect
			(at 0.50038 -2.0701 180)
			(size 0.3048 1.524)
			(layers "F.Cu" "F.Mask" "F.Paste")
			(net "P12VL")
		)
		(pad "8" smd rect
			(at 0 -2.0701 180)
			(size 0.3048 1.524)
			(layers "F.Cu" "F.Mask" "F.Paste")
			(net "P12VL_2490_GATE")
		)
		(pad "9" smd rect
			(at -0.50038 -2.0701 180)
			(size 0.3048 1.524)
			(layers "F.Cu" "F.Mask" "F.Paste")
			(net "P12VL_2490_SENSE")
		)
		(pad "10" smd rect
			(at -0.99949 -2.0701 180)
			(size 0.3048 1.524)
			(layers "F.Cu" "F.Mask" "F.Paste")
			(net "P12VL_2490_VCC")
		)
	)
	(footprint ""
		(layer "F.Cu")
		(at 20.675092 -285.598362 180)
		(property "Reference" "R94"
			(at 0 0 180)
			(layer "F.SilkS")
			(hide yes)
			(effects
				(font
					(size 1.27 1.27)
				)
			)
		)
		(property "Value" "4K7R2F-GP"
			(at 0.064008 -3.993896 180)
			(unlocked yes)
			(layer "F.Fab")
			(hide yes)
			(effects
				(font
					(size 1.016 1.016)
					(thickness 0.1524)
				)
			)
		)
		(property "Device Type" "R402H16"
			(at 0.064008 -5.517896 180)
			(unlocked yes)
			(layer "F.Fab")
			(hide yes)
			(effects
				(font
					(size 1.016 1.016)
					(thickness 0.1524)
				)
			)
		)
		(duplicate_pad_numbers_are_jumpers no)
		(fp_line
			(start 0.508 -0.9398)
			(end -0.508 -0.9398)
			(stroke
				(width 0.1524)
				(type default)
			)
			(layer "F.SilkS")
		)
		(fp_line
			(start -0.508 -0.9398)
			(end -0.508 0.9398)
			(stroke
				(width 0.1524)
				(type default)
			)
			(layer "F.SilkS")
		)
		(fp_rect
			(start -0.508 0.9398)
			(end 0.508 -0.9398)
			(stroke
				(width 0)
				(type default)
			)
			(fill no)
			(layer "F.CrtYd")
		)
		(fp_rect
			(start -0.508 0.9398)
			(end 0.508 -0.9398)
			(stroke
				(width 0)
				(type default)
			)
			(fill no)
			(layer "F.Fab")
		)
		(pad "1" smd custom
			(at 0 -0.4445 180)
			(size 0.1397 0.1397)
			(layers "F.Cu" "F.Mask" "F.Paste")
			(net "P12V")
			(options
				(clearance outline)
				(anchor circle)
			)
			(primitives
				(gr_poly
					(pts
						(arc
							(start -0.1778 -0.2794)
							(mid -0.249642 -0.249642)
							(end -0.2794 -0.1778)
						)
						(arc
							(start -0.2794 0.1778)
							(mid -0.249642 0.249642)
							(end -0.1778 0.2794)
						)
						(arc
							(start 0.1778 0.2794)
							(mid 0.249642 0.249642)
							(end 0.2794 0.1778)
						)
						(arc
							(start 0.2794 -0.1778)
							(mid 0.249642 -0.249642)
							(end 0.1778 -0.2794)
						)
					)
					(width 0)
					(fill yes)
				)
			)
		)
		(pad "2" smd custom
			(at 0 0.4445 180)
			(size 0.1397 0.1397)
			(layers "F.Cu" "F.Mask" "F.Paste")
			(net "FAN_TACH4")
			(options
				(clearance outline)
				(anchor circle)
			)
			(primitives
				(gr_poly
					(pts
						(arc
							(start -0.1778 -0.2794)
							(mid -0.249642 -0.249642)
							(end -0.2794 -0.1778)
						)
						(arc
							(start -0.2794 0.1778)
							(mid -0.249642 0.249642)
							(end -0.1778 0.2794)
						)
						(arc
							(start 0.1778 0.2794)
							(mid 0.249642 0.249642)
							(end 0.2794 0.1778)
						)
						(arc
							(start 0.2794 -0.1778)
							(mid 0.249642 -0.249642)
							(end 0.1778 -0.2794)
						)
					)
					(width 0)
					(fill yes)
				)
			)
		)
	)
	(footprint ""
		(layer "F.Cu")
		(at 32.85109 -167.723566 180)
		(property "Reference" "R7"
			(at 0 0 180)
			(layer "F.SilkS")
			(hide yes)
			(effects
				(font
					(size 1.27 1.27)
				)
			)
		)
		(property "Value" "0R2J-2-GP"
			(at 0.064008 -3.993896 180)
			(unlocked yes)
			(layer "F.Fab")
			(hide yes)
			(effects
				(font
					(size 1.016 1.016)
					(thickness 0.1524)
				)
			)
		)
		(property "Device Type" "R402H16"
			(at 0.064008 -5.517896 180)
			(unlocked yes)
			(layer "F.Fab")
			(hide yes)
			(effects
				(font
					(size 1.016 1.016)
					(thickness 0.1524)
				)
			)
		)
		(duplicate_pad_numbers_are_jumpers no)
		(fp_line
			(start 0.508 -0.9398)
			(end -0.508 -0.9398)
			(stroke
				(width 0.1524)
				(type default)
			)
			(layer "F.SilkS")
		)
		(fp_line
			(start -0.508 -0.9398)
			(end -0.508 0.9398)
			(stroke
				(width 0.1524)
				(type default)
			)
			(layer "F.SilkS")
		)
		(fp_rect
			(start -0.508 0.9398)
			(end 0.508 -0.9398)
			(stroke
				(width 0)
				(type default)
			)
			(fill no)
			(layer "F.CrtYd")
		)
		(fp_rect
			(start -0.508 0.9398)
			(end 0.508 -0.9398)
			(stroke
				(width 0)
				(type default)
			)
			(fill no)
			(layer "F.Fab")
		)
		(pad "1" smd custom
			(at 0 -0.4445 180)
			(size 0.1397 0.1397)
			(layers "F.Cu" "F.Mask" "F.Paste")
			(net "NCT7904_RSTOUT")
			(options
				(clearance outline)
				(anchor circle)
			)
			(primitives
				(gr_poly
					(pts
						(arc
							(start -0.1778 -0.2794)
							(mid -0.249642 -0.249642)
							(end -0.2794 -0.1778)
						)
						(arc
							(start -0.2794 0.1778)
							(mid -0.249642 0.249642)
							(end -0.1778 0.2794)
						)
						(arc
							(start 0.1778 0.2794)
							(mid 0.249642 0.249642)
							(end 0.2794 0.1778)
						)
						(arc
							(start 0.2794 -0.1778)
							(mid 0.249642 -0.249642)
							(end 0.1778 -0.2794)
						)
					)
					(width 0)
					(fill yes)
				)
			)
		)
		(pad "2" smd custom
			(at 0 0.4445 180)
			(size 0.1397 0.1397)
			(layers "F.Cu" "F.Mask" "F.Paste")
			(net "TEMP_ALM#")
			(options
				(clearance outline)
				(anchor circle)
			)
			(primitives
				(gr_poly
					(pts
						(arc
							(start -0.1778 -0.2794)
							(mid -0.249642 -0.249642)
							(end -0.2794 -0.1778)
						)
						(arc
							(start -0.2794 0.1778)
							(mid -0.249642 0.249642)
							(end -0.1778 0.2794)
						)
						(arc
							(start 0.1778 0.2794)
							(mid 0.249642 0.249642)
							(end 0.2794 0.1778)
						)
						(arc
							(start 0.2794 -0.1778)
							(mid 0.249642 -0.249642)
							(end 0.1778 -0.2794)
						)
					)
					(width 0)
					(fill yes)
				)
			)
		)
	)
	(footprint ""
		(layer "F.Cu")
		(at 36.5252 -254.381)
		(property "Reference" "R48"
			(at 0 0 0)
			(layer "F.SilkS")
			(hide yes)
			(effects
				(font
					(size 1.27 1.27)
				)
			)
		)
		(property "Value" "4K7R2J-2-GP"
			(at 0.064008 -3.993896 0)
			(unlocked yes)
			(layer "F.Fab")
			(hide yes)
			(effects
				(font
					(size 1.016 1.016)
					(thickness 0.1524)
				)
			)
		)
		(property "Device Type" "R402H16"
			(at 0.064008 -5.517896 0)
			(unlocked yes)
			(layer "F.Fab")
			(hide yes)
			(effects
				(font
					(size 1.016 1.016)
					(thickness 0.1524)
				)
			)
		)
		(duplicate_pad_numbers_are_jumpers no)
		(fp_line
			(start -0.508 -0.9398)
			(end -0.508 0.9398)
			(stroke
				(width 0.1524)
				(type default)
			)
			(layer "F.SilkS")
		)
		(fp_line
			(start 0.508 -0.9398)
			(end -0.508 -0.9398)
			(stroke
				(width 0.1524)
				(type default)
			)
			(layer "F.SilkS")
		)
		(fp_rect
			(start -0.508 0.9398)
			(end 0.508 -0.9398)
			(stroke
				(width 0)
				(type default)
			)
			(fill no)
			(layer "F.CrtYd")
		)
		(fp_rect
			(start -0.508 0.9398)
			(end 0.508 -0.9398)
			(stroke
				(width 0)
				(type default)
			)
			(fill no)
			(layer "F.Fab")
		)
		(pad "1" smd custom
			(at 0 -0.4445)
			(size 0.1397 0.1397)
			(layers "F.Cu" "F.Mask" "F.Paste")
			(net "P3V3")
			(options
				(clearance outline)
				(anchor circle)
			)
			(primitives
				(gr_poly
					(pts
						(arc
							(start -0.1778 -0.2794)
							(mid -0.249642 -0.249642)
							(end -0.2794 -0.1778)
						)
						(arc
							(start -0.2794 0.1778)
							(mid -0.249642 0.249642)
							(end -0.1778 0.2794)
						)
						(arc
							(start 0.1778 0.2794)
							(mid 0.249642 0.249642)
							(end 0.2794 0.1778)
						)
						(arc
							(start 0.2794 -0.1778)
							(mid 0.249642 -0.249642)
							(end 0.1778 -0.2794)
						)
					)
					(width 0)
					(fill yes)
				)
			)
		)
		(pad "2" smd custom
			(at 0 0.4445)
			(size 0.1397 0.1397)
			(layers "F.Cu" "F.Mask" "F.Paste")
			(net "LED_DRV_RST")
			(options
				(clearance outline)
				(anchor circle)
			)
			(primitives
				(gr_poly
					(pts
						(arc
							(start -0.1778 -0.2794)
							(mid -0.249642 -0.249642)
							(end -0.2794 -0.1778)
						)
						(arc
							(start -0.2794 0.1778)
							(mid -0.249642 0.249642)
							(end -0.1778 0.2794)
						)
						(arc
							(start 0.1778 0.2794)
							(mid 0.249642 0.249642)
							(end 0.2794 0.1778)
						)
						(arc
							(start 0.2794 -0.1778)
							(mid 0.249642 -0.249642)
							(end 0.1778 -0.2794)
						)
					)
					(width 0)
					(fill yes)
				)
			)
		)
	)
	(footprint ""
		(layer "F.Cu")
		(at 41.529 -183.185816)
		(property "Reference" "U8"
			(at 0 0 0)
			(layer "F.SilkS")
			(hide yes)
			(effects
				(font
					(size 1.27 1.27)
				)
			)
		)
		(property "Value" "TSAHC74PWR-GP"
			(at -7.112 -6.0579 0)
			(unlocked yes)
			(layer "F.Fab")
			(hide yes)
			(effects
				(font
					(size 1.016 1.016)
					(thickness 0.1524)
				)
			)
		)
		(property "Device Type" "TSOIC14H48"
			(at -7.112 -7.5819 0)
			(unlocked yes)
			(layer "F.Fab")
			(hide yes)
			(effects
				(font
					(size 1.016 1.016)
					(thickness 0.1524)
				)
			)
		)
		(duplicate_pad_numbers_are_jumpers no)
		(fp_line
			(start -2.9718 -1.778)
			(end 2.1336 -1.778)
			(stroke
				(width 0.1524)
				(type default)
			)
			(layer "F.SilkS")
		)
		(fp_line
			(start -2.9718 1.778)
			(end -2.9718 -1.778)
			(stroke
				(width 0.1524)
				(type default)
			)
			(layer "F.SilkS")
		)
		(fp_line
			(start -2.9337 -0.4699)
			(end -2.9083 -0.4699)
			(stroke
				(width 0.1524)
				(type default)
			)
			(layer "F.SilkS")
		)
		(fp_line
			(start -2.9083 -0.4699)
			(end -2.4384 0)
			(stroke
				(width 0.1524)
				(type default)
			)
			(layer "F.SilkS")
		)
		(fp_line
			(start -2.8956 0.4572)
			(end -2.921 0.4572)
			(stroke
				(width 0.1524)
				(type default)
			)
			(layer "F.SilkS")
		)
		(fp_line
			(start -2.794 3.8227)
			(end -2.794 1.7018)
			(stroke
				(width 0.508)
				(type default)
			)
			(layer "F.SilkS")
		)
		(fp_line
			(start -2.4384 0)
			(end -2.8956 0.4572)
			(stroke
				(width 0.1524)
				(type default)
			)
			(layer "F.SilkS")
		)
		(fp_line
			(start 2.1336 -1.778)
			(end 2.1336 1.778)
			(stroke
				(width 0.1524)
				(type default)
			)
			(layer "F.SilkS")
		)
		(fp_line
			(start 2.1336 1.778)
			(end -2.9718 1.778)
			(stroke
				(width 0.1524)
				(type default)
			)
			(layer "F.SilkS")
		)
		(fp_poly
			(pts
				(xy -2.1336 -1.7653) (xy 2.1336 -1.7653) (xy 2.1336 1.778) (xy -2.1336 1.778)
			)
			(stroke
				(width 0)
				(type default)
			)
			(fill yes)
			(layer "F.SilkS")
		)
		(fp_rect
			(start -2.5019 3.2004)
			(end 2.5019 -3.2004)
			(stroke
				(width 0)
				(type default)
			)
			(fill no)
			(layer "F.CrtYd")
		)
		(fp_poly
			(pts
				(xy -3.048 4.0894) (xy -3.048 -2.5781) (xy -2.5019 -2.5781) (xy -2.5019 3.2004) (xy 2.5019 3.2004)
				(xy 2.5019 -3.2004) (xy -2.5019 -3.2004) (xy -2.5019 -2.5908) (xy -3.048 -2.5908) (xy -3.048 -4.0894)
				(xy 3.048 -4.0894) (xy 3.048 4.0894)
			)
			(stroke
				(width 0)
				(type default)
			)
			(fill no)
			(layer "F.CrtYd")
		)
		(fp_rect
			(start -3.048 4.0894)
			(end 3.048 -4.0894)
			(stroke
				(width 0)
				(type default)
			)
			(fill no)
			(layer "F.Fab")
		)
		(pad "1" smd rect
			(at -1.94945 2.8194)
			(size 0.3556 1.524)
			(layers "F.Cu" "F.Mask" "F.Paste")
			(net "D_LATCH_CLR")
		)
		(pad "2" smd rect
			(at -1.30048 2.8194)
			(size 0.3556 1.524)
			(layers "F.Cu" "F.Mask" "F.Paste")
			(net "GND")
		)
		(pad "3" smd rect
			(at -0.65024 2.8194)
			(size 0.3556 1.524)
			(layers "F.Cu" "F.Mask" "F.Paste")
			(net "TEMP_ALM#_IN_D")
		)
		(pad "4" smd rect
			(at 0 2.8194)
			(size 0.3556 1.524)
			(layers "F.Cu" "F.Mask" "F.Paste")
			(net "D_LATCH_PRE#")
		)
		(pad "5" smd rect
			(at 0.65024 2.8194)
			(size 0.3556 1.524)
			(layers "F.Cu" "F.Mask" "F.Paste")
			(net "D_LATCH_Q")
		)
		(pad "6" smd rect
			(at 1.30048 2.8194)
			(size 0.3556 1.524)
			(layers "F.Cu" "F.Mask" "F.Paste")
			(net "D_LATCH_Q#")
		)
		(pad "7" smd rect
			(at 1.94945 2.8194)
			(size 0.3556 1.524)
			(layers "F.Cu" "F.Mask" "F.Paste")
			(net "GND")
		)
		(pad "8" smd rect
			(at 1.94945 -2.8194)
			(size 0.3556 1.524)
			(layers "F.Cu" "F.Mask" "F.Paste")
			(net "Net_58")
		)
		(pad "9" smd rect
			(at 1.30048 -2.8194)
			(size 0.3556 1.524)
			(layers "F.Cu" "F.Mask" "F.Paste")
			(net "Net_59")
		)
		(pad "10" smd rect
			(at 0.65024 -2.8194)
			(size 0.3556 1.524)
			(layers "F.Cu" "F.Mask" "F.Paste")
			(net "P3V3_AUX")
		)
		(pad "11" smd rect
			(at 0 -2.8194)
			(size 0.3556 1.524)
			(layers "F.Cu" "F.Mask" "F.Paste")
			(net "GND")
		)
		(pad "12" smd rect
			(at -0.65024 -2.8194)
			(size 0.3556 1.524)
			(layers "F.Cu" "F.Mask" "F.Paste")
			(net "GND")
		)
		(pad "13" smd rect
			(at -1.30048 -2.8194)
			(size 0.3556 1.524)
			(layers "F.Cu" "F.Mask" "F.Paste")
			(net "P3V3_AUX")
		)
		(pad "14" smd rect
			(at -1.94945 -2.8194)
			(size 0.3556 1.524)
			(layers "F.Cu" "F.Mask" "F.Paste")
			(net "P3V3_AUX")
		)
	)
	(footprint ""
		(layer "F.Cu")
		(at 37.5666 -254.3556)
		(property "Reference" "R59"
			(at 0 0 0)
			(layer "F.SilkS")
			(hide yes)
			(effects
				(font
					(size 1.27 1.27)
				)
			)
		)
		(property "Value" "330R2J-3-GP"
			(at 0.064008 -3.993896 0)
			(unlocked yes)
			(layer "F.Fab")
			(hide yes)
			(effects
				(font
					(size 1.016 1.016)
					(thickness 0.1524)
				)
			)
		)
		(property "Device Type" "R402H16"
			(at 0.064008 -5.517896 0)
			(unlocked yes)
			(layer "F.Fab")
			(hide yes)
			(effects
				(font
					(size 1.016 1.016)
					(thickness 0.1524)
				)
			)
		)
		(duplicate_pad_numbers_are_jumpers no)
		(fp_line
			(start -0.508 -0.9398)
			(end -0.508 0.9398)
			(stroke
				(width 0.1524)
				(type default)
			)
			(layer "F.SilkS")
		)
		(fp_line
			(start 0.508 -0.9398)
			(end -0.508 -0.9398)
			(stroke
				(width 0.1524)
				(type default)
			)
			(layer "F.SilkS")
		)
		(fp_rect
			(start -0.508 0.9398)
			(end 0.508 -0.9398)
			(stroke
				(width 0)
				(type default)
			)
			(fill no)
			(layer "F.CrtYd")
		)
		(fp_rect
			(start -0.508 0.9398)
			(end 0.508 -0.9398)
			(stroke
				(width 0)
				(type default)
			)
			(fill no)
			(layer "F.Fab")
		)
		(pad "1" smd custom
			(at 0 -0.4445)
			(size 0.1397 0.1397)
			(layers "F.Cu" "F.Mask" "F.Paste")
			(net "P3V3")
			(options
				(clearance outline)
				(anchor circle)
			)
			(primitives
				(gr_poly
					(pts
						(arc
							(start -0.1778 -0.2794)
							(mid -0.249642 -0.249642)
							(end -0.2794 -0.1778)
						)
						(arc
							(start -0.2794 0.1778)
							(mid -0.249642 0.249642)
							(end -0.1778 0.2794)
						)
						(arc
							(start 0.1778 0.2794)
							(mid 0.249642 0.249642)
							(end 0.2794 0.1778)
						)
						(arc
							(start 0.2794 -0.1778)
							(mid 0.249642 -0.249642)
							(end 0.1778 -0.2794)
						)
					)
					(width 0)
					(fill yes)
				)
			)
		)
		(pad "2" smd custom
			(at 0 0.4445)
			(size 0.1397 0.1397)
			(layers "F.Cu" "F.Mask" "F.Paste")
			(net "LED_DR_LED7_RESERVE")
			(options
				(clearance outline)
				(anchor circle)
			)
			(primitives
				(gr_poly
					(pts
						(arc
							(start -0.1778 -0.2794)
							(mid -0.249642 -0.249642)
							(end -0.2794 -0.1778)
						)
						(arc
							(start -0.2794 0.1778)
							(mid -0.249642 0.249642)
							(end -0.1778 0.2794)
						)
						(arc
							(start 0.1778 0.2794)
							(mid 0.249642 0.249642)
							(end 0.2794 0.1778)
						)
						(arc
							(start 0.2794 -0.1778)
							(mid 0.249642 -0.249642)
							(end 0.1778 -0.2794)
						)
					)
					(width 0)
					(fill yes)
				)
			)
		)
	)
)
